#ISCELL
  mstr_misc dns *
  *
#ISCELL
  pure_quanta quanta_title_block_c *
  *
#ISCELL
  logical_power universal_gnd *
  page272_i1
#CELL
  pure_quanta isl99390frztr5935 *
  page272_i10
#CELL
  pure_quanta q_cap *
  page272_i11
#CELL
  pure_quanta q_res *
  page272_i12
#ISCELL
  logical_power vcc15 *
  page272_i13
#ISCELL
  logical_power universal_gnd *
  page272_i14
#CELL
  pure_quanta q_res *
  page272_i15
#ISCELL
  standard offpage *
  page272_i16
#ISCELL
  standard offpage *
  page272_i17
#ISCELL
  logical_power universal_gnd *
  page272_i18
#CELL
  pure_quanta q_cap *
  page272_i19
#ISCELL
  logical_power universal_gnd *
  page272_i2
#ISCELL
  logical_power universal_gnd *
  page272_i20
#ISCELL
  standard offpage *
  page272_i21
#ISCELL
  standard offpage *
  page272_i22
#ISCELL
  logical_power universal_gnd *
  page272_i23
#CELL
  pure_quanta q_cap *
  page272_i24
#CELL
  pure_quanta q_res *
  page272_i25
#ISCELL
  logical_power vcc15 *
  page272_i26
#CELL
  pure_quanta q_cap *
  page272_i27
#ISCELL
  logical_power universal_gnd *
  page272_i28
#CELL
  pure_quanta q_cap *
  page272_i29
#CELL
  pure_quanta q_res *
  page272_i3
#ISCELL
  logical_power universal_gnd *
  page272_i30
#ISCELL
  standard offpage *
  page272_i31
#ISCELL
  logical_power universal_gnd *
  page272_i32
#CELL
  pure_quanta q_cap *
  page272_i33
#CELL
  pure_quanta q_res *
  page272_i34
#CELL
  pure_quanta q_cap *
  page272_i35
#CELL
  pure_quanta q_cap *
  page272_i36
#CELL
  pure_quanta q_inductor4p_14 *
  page272_i37
#CELL
  pure_quanta q_res *
  page272_i38
#CELL
  pure_quanta q_cap *
  page272_i39
#ISCELL
  standard offpage *
  page272_i4
#ISCELL
  standard offpage *
  page272_i40
#CELL
  pure_quanta q_cap *
  page272_i41
#CELL
  pure_quanta q_cap *
  page272_i42
#ISCELL
  logical_power universal_gnd *
  page272_i43
#ISCELL
  logical_power vcc15 *
  page272_i44
#CELL
  pure_quanta q_res *
  page272_i45
#CELL
  pure_quanta q_res *
  page272_i46
#ISCELL
  standard offpage *
  page272_i47
#CELL
  pure_quanta q_cap *
  page272_i48
#CELL
  pure_quanta q_cap *
  page272_i49
#ISCELL
  standard offpage *
  page272_i5
#CELL
  pure_quanta q_cap *
  page272_i50
#CELL
  pure_quanta q_inductor4p_14 *
  page272_i51
#CELL
  pure_quanta q_cap *
  page272_i52
#ISCELL
  logical_power universal_gnd *
  page272_i53
#CELL
  pure_quanta q_cap *
  page272_i54
#CELL
  pure_quanta q_cap *
  page272_i55
#ISCELL
  logical_power vcc15 *
  page272_i56
#ISCELL
  standard offpage *
  page272_i57
#CELL
  pure_quanta q_cap *
  page272_i58
#CELL
  pure_quanta q_cap *
  page272_i59
#CELL
  pure_quanta q_cap *
  page272_i6
#ISCELL
  logical_power universal_gnd *
  page272_i60
#ISCELL
  logical_power vcc15 *
  page272_i61
#ISCELL
  logical_power universal_gnd *
  page272_i62
#CELL
  pure_quanta q_cap *
  page272_i63
#CELL
  pure_quanta q_cap *
  page272_i64
#ISCELL
  logical_power vcc15 *
  page272_i65
#CELL
  pure_quanta isl99390frztr5935 *
  page272_i66
#ISCELL
  standard offpage *
  page272_i7
#ISCELL
  standard offpage *
  page272_i8
#ISCELL
  logical_power universal_gnd *
  page272_i9
